# SCM (Grand Teton) — schematic parts with pin connectivity, parts 679–842 of 1428; source: Cadence DE-HDL packaged netlist (pstxprt.dat, pstxnet.dat, pstchip.dat)

R173  Q_RES  22 1% CHIP  pkg 0402LF  page 13 : 1 = RMII_TXD1_R ; 2 = RMII_TXD1
R174  Q_RES  33.2 1% CHIP  pkg 0402LF  page 44 : 1 = SPI_BMC_BIOS_ROM_CLK ; 2 = SPI_BMC_BIOS_ROM_R_CLK
R175  Q_RES  33.2 1% CHIP  pkg 0402LF  page 44 : 1 = SPI_BMC_BIOS_ROM_MOSI ; 2 = SPI_BMC_BIOS_ROM_R_MOSI
R176  Q_RES  33.2 1% CHIP  pkg 0402LF  page 44 : 1 = SPI_BMC_BIOS_ROM_MISO ; 2 = SPI_BMC_BIOS_ROM_R_MISO
R177  Q_RES  33.2 1% CHIP  pkg 0402LF  page 13 : 1 = H_CPU1_PROCHOT_LVC1_N ; 2 = H_CPU1_PROCHOT_LVC1_R_N
R178  Q_RES  33.2 1% CHIP  pkg 0402LF  page 13 : 1 = SPI_BMC_CLK_R ; 2 = SPI_BMC_BOOT_CLK
R179  Q_RES  33.2 1% CHIP  pkg 0402LF  page 13 : 1 = SPI_BMC_MOSI_IO0_R ; 2 = SPI_BMC_BOOT_MOSI
R180  Q_RES  33.2 1% CHIP  pkg 0402LF  page 13 : 1 = SPI_BMC_MISO_IO1_R ; 2 = SPI_BMC_BOOT_MISO
R181  Q_RES  4.7K 1% CHIP  pkg 0402LF  page 25 : 1 = P3V3_AUX ; 2 = FM_FLASH_LATCH_N
R182  Q_RES  0 5% CHIP  pkg 0402LF  page 25 : 1 = GND ; 2 = FLASH_LATCH_D
R183  Q_RES  0 5% CHIP  pkg 0402LF  page 34 : 1 = P3V3_AUX ; 2 = PVCCIO_AUX_PLD
R184  Q_RES  110 1% CHIP  pkg 0402LF  page 14 : 1 = I3C1_SPD_SCL ; 2 = I3C1_SCL_R
R185  Q_RES  33.2 1% CHIP  pkg 0402LF  page 14 : 1 = I3C1_SPD_SDA ; 2 = I3C1_SDA_R
R186  Q_RES  110 1% CHIP  pkg 0402LF  page 14 : 1 = I3C2_SPD_SCL ; 2 = I3C2_SCL_R
R187  Q_RES  33.2 1% CHIP  pkg 0402LF  page 14 : 1 = I3C2_SPD_SDA ; 2 = I3C2_SDA_R
R188  Q_RES  1K 1% CHIP  pkg 0402LF  page 14 : 1 = P1V2_P1V0_I3C_VDDL1 ; 2 = I3C3_SPD_SCL
R189  Q_RES  1K 1% CHIP  pkg 0402LF  page 14 : 1 = P1V2_P1V0_I3C_VDDL1 ; 2 = I3C3_SPD_SDA
R190  Q_RES  1K 1% CHIP  pkg 0402LF  page 14 : 1 = P1V2_P1V0_I3C_VDDL1 ; 2 = I3C2_SPD_SCL
R191  Q_RES  1K 1% CHIP  pkg 0402LF  page 14 : 1 = P1V2_P1V0_I3C_VDDL1 ; 2 = I3C2_SPD_SDA
R192  Q_RES  49.9 1% CHIP  pkg 0402LF  page 22 : 1 = PWRGD_P1V0_AUX_DELAY_BUF ; 2 = RST_BMC_SRST_BUF_R_N
R193  Q_RES  100K 1% CHIP  pkg 0402LF  page 29 : 1 = P3V3_AUX ; 2 = SPA_SIN_SW_DBG
R194  Q_RES  1K 1% CHIP  pkg 0402LF  page 14 : 1 = P1V2_P1V0_I3C_VDDL1 ; 2 = I3C1_SPD_SCL
R195  Q_RES  1K 1% CHIP  pkg 0402LF  page 14 : 1 = P1V2_P1V0_I3C_VDDL1 ; 2 = I3C1_SPD_SDA
R196  Q_RES  1K 1% CHIP  pkg 0402LF  page 14 : 1 = P1V2_P1V0_I3C_VDDL1 ; 2 = I3C4_SPD_SCL
R197  Q_RES  1K 1% CHIP  pkg 0402LF  page 14 : 1 = P1V2_P1V0_I3C_VDDL1 ; 2 = I3C4_SPD_SDA
R198  Q_RES  110 1% CHIP  pkg 0402LF  page 14 : 1 = I3C3_SCL_R ; 2 = I3C3_SPD_SCL
R199  Q_RES  33.2 1% CHIP  pkg 0402LF  page 14 : 1 = I3C3_SDA_R ; 2 = I3C3_SPD_SDA
R200  Q_RES  110 1% CHIP  pkg 0402LF  page 14 : 1 = I3C4_SCL_R ; 2 = I3C4_SPD_SCL
R201  Q_RES  33.2 1% CHIP  pkg 0402LF  page 14 : 1 = I3C4_SDA_R ; 2 = I3C4_SPD_SDA
R202  Q_RES  10K 1% EMPTY  pkg 0402LF  page 32 : 1 = GND ; 2 = JTAG_SCM_TCK
R203  Q_RES  10K 1% CHIP  pkg 0402LF  page 32 : 1 = P3V3_RGM ; 2 = JTAG_SCM_TMS
R204  Q_RES  10K 1% CHIP  pkg 0402LF  page 32 : 1 = P3V3_RGM ; 2 = JTAG_SCM_TDI
R205  Q_RES  20K 1% CHIP  pkg 0402LF  page 29 : 1 = DEBUG_PORT_PRSNT_R ; 2 = GND
R206  Q_RES  10K 1% CHIP  pkg 0402LF  page 32 : 1 = GND ; 2 = JTAG_SCM_NTRST
R207  Q_RES  0 5% CHIP  pkg 0402LF  page 15 : 1 = P3V3_AUX ; 2 = P3V3_P1V8_SD1VDD
R208  Q_RES  0 5% EMPTY  pkg 0402LF  page 15 : 1 = P1V8_AUX ; 2 = P3V3_P1V8_SD1VDD
R209  Q_RES  10K 1% EMPTY  pkg 0402LF  page 15 : 1 = PECI_BMC ; 2 = GND
R210  Q_RES  1K 1% CHIP  pkg 0402LF  page 15 : 1 = GND ; 2 = PD_SP_ENTEST
R211  Q_RES  10K 1% CHIP  pkg 0402LF  page 15 : 1 = P3V3_RGM ; 2 = FM_BMC_SSPRST_N
R212  Q_RES  4.7K 1% CHIP  pkg 0402LF  page 15 : 1 = P3V3_RGM ; 2 = PU_25M_BMC_CLK_EN
R213  Q_RES  0 5% CHIP  pkg 0402LF  page 15 : 1 = P3V3_AUX ; 2 = P3V3_P1V8_SD2VDD
R214  Q_RES  0 5% EMPTY  pkg 0402LF  page 15 : 1 = P1V8_AUX ; 2 = P3V3_P1V8_SD2VDD
R215  Q_RES  33.2 1% CHIP  pkg 0402LF  page 15 : 1 = BMC_CLK_25M_R ; 2 = BMC_CLK_25M
R216  Q_RES  49.9 1% CHIP  pkg 0402LF  page 15 : 1 = PECI_BMC_R ; 2 = PECI_BMC
R217  Q_RES  0 5% CHIP  pkg 0402LF  page 15 : 1 = USB_HOST_BMC_A_R_DP ; 2 = USB_HOST_BMC_A_DP
R218  Q_RES  0 5% CHIP  pkg 0402LF  page 15 : 1 = USB_HOST_BMC_A_R_DN ; 2 = USB_HOST_BMC_A_DN
R219  Q_RES  100K 1% EMPTY  pkg 0402LF  page 29 : 1 = DEBUG_PORT_UART_TX ; 2 = GND
R220  Q_RES  0 5% CHIP  pkg 0402LF  page 36 : 1 = FM_BMC_UARTSW_MSB_N ; 2 = FM_UARTSW_MSB_N
R221  Q_RES  33.2 1% CHIP  pkg 0402LF  page 32 : 1 = JTAG_1_BMC_TRST_R ; 2 = JTAG_MB_TRST_N
R222  Q_RES  33.2 1% CHIP  pkg 0402LF  page 32 : 1 = JTAG_1_BMC_TCK_R ; 2 = JTAG_MB_TCK
R223  Q_RES  33.2 1% CHIP  pkg 0402LF  page 32 : 1 = JTAG_1_BMC_TMS_R ; 2 = JTAG_MB_TMS
R224  Q_RES  33.2 1% CHIP  pkg 0402LF  page 32 : 1 = JTAG_1_BMC_TDO_R ; 2 = JTAG_MB_TDO
R225  Q_RES  100 1% CHIP  pkg 0402LF  page 15 : 1 = FM_PWR_BTN ; 2 = PWR_BTN_BMC_N
R226  Q_RES  10K 1% CHIP  pkg 0402LF  page 32 : 1 = P3V3_AUX ; 2 = JTAG_MB_TDI
R227  Q_RES  10K 1% CHIP  pkg 0402LF  page 32 : 1 = P3V3_AUX ; 2 = JTAG_MB_TMS
R228  Q_RES  10K 1% EMPTY  pkg 0402LF  page 32 : 1 = GND ; 2 = JTAG_MB_TCK
R229  Q_RES  4.7K 1% EMPTY  pkg 0402LF  page 32 : 1 = GND ; 2 = JTAG_MB_TRST_N
R230  Q_RES  10K 1% CHIP  pkg 0402LF  page 32 : 1 = P3V3_AUX ; 2 = JTAG_MB_TDO
R231  Q_RES  0 5% CHIP  pkg 0402LF  page 17 : 1 = P3V3_AUX ; 2 = P3V3_P1V8_I2C_I3C
R232  Q_RES  0 5% EMPTY  pkg 0402LF  page 17 : 1 = P1V8_AUX ; 2 = P3V3_P1V8_I2C_I3C
R233  Q_RES  49.9K 1% CHIP  pkg 0402LF  page 16 : 1 = GND ; 2 = A_BMC_ADCREXT0
R234  Q_RES  49.9K 1% CHIP  pkg 0402LF  page 16 : 1 = GND ; 2 = A_BMC_ADCREXT1
R235  Q_RES  2.74K 1% CHIP  pkg 0402LF  page 16 : 1 = GND ; 2 = A_BMC_DACREST
R236  Q_RES  33.2 1% CHIP  pkg 0402LF  page 12 : 1 = SMB_BMC_MM15_SDA ; 2 = SMB_BMC_MM15_R_SDA
R237  Q_RES  33.2 1% CHIP  pkg 0402LF  page 13 : 1 = FM_DBP_BMC_PRDY_N ; 2 = FM_DBP_BMC_PRDY_R_N
R238  Q_RES  4.7K 1% CHIP  pkg 0402LF  page 13 : 1 = P3V3_AUX ; 2 = SPI_BMC_TPM_CS2_R_N
R239  Q_RES  4.7K 1% CHIP  pkg 0402LF  page 13 : 1 = P3V3_AUX ; 2 = PU_BMC_FWSPIABR_N
R240  Q_RES  4.7K 1% CHIP  pkg 0402LF  page 13 : 1 = P3V3_AUX ; 2 = PU_FWSPIWP_N
R241  Q_RES  4.7K 1% CHIP  pkg 0402LF  page 13 : 1 = P3V3_AUX ; 2 = PU_SPI1ABR
R242  Q_RES  33.2 1% CHIP  pkg 0402LF  page 13 : 1 = FM_BMC_CPU_FBRK_OUT_N ; 2 = FM_BMC_CPU_FBRK_OUT_R_N
R243  Q_RES  33.2 1% CHIP  pkg 0402LF  page 10 : 1 = PWRGD_PSU_AC_PWROK ; 2 = PWRGD_PSU_AC_PWROK_R
R244  Q_RES  1.8K 1% CHIP  pkg 0402LF  page 27 : 1 = P3V3_AUX ; 2 = SMB_BMC_MM1_SCL
R245  Q_RES  1.8K 1% CHIP  pkg 0402LF  page 27 : 1 = P3V3_AUX ; 2 = SMB_BMC_MM1_SDA
R246  Q_RES  2.2K 5% CHIP  pkg 0402LF  page 27 : 1 = P3V3_AUX ; 2 = SMB_BMC_MM2_SCL
R247  Q_RES  2.2K 5% CHIP  pkg 0402LF  page 27 : 1 = P3V3_AUX ; 2 = SMB_BMC_MM2_SDA
R248  Q_RES  2.2K 5% CHIP  pkg 0402LF  page 27 : 1 = P3V3_AUX ; 2 = SMB_BMC_MM3_SCL
R249  Q_RES  2.2K 5% CHIP  pkg 0402LF  page 27 : 1 = P3V3_AUX ; 2 = SMB_BMC_MM3_SDA
R250  Q_RES  402 1% CHIP  pkg 0402LF  page 27 : 1 = P3V3_AUX ; 2 = SMB_BMC_MM4_SCL
R251  Q_RES  499 1% CHIP  pkg 0402LF  page 27 : 1 = P3V3_AUX ; 2 = SMB_BMC_MM4_SDA
R252  Q_RES  2.2K 5% CHIP  pkg 0402LF  page 27 : 1 = P3V3_AUX ; 2 = SMB_BMC_MM5_R_SCL
R253  Q_RES  2.2K 5% CHIP  pkg 0402LF  page 27 : 1 = P3V3_AUX ; 2 = SMB_BMC_MM5_R_SDA
R254  Q_RES  10K 1% CHIP  pkg 0402LF  page 27 : 1 = P3V3_AUX ; 2 = SMB_BMC_MM6_SCL
R255  Q_RES  10K 1% CHIP  pkg 0402LF  page 27 : 1 = P3V3_AUX ; 2 = SMB_BMC_MM6_SDA
R256  Q_RES  2.2K 5% CHIP  pkg 0402LF  page 27 : 1 = P3V3_AUX ; 2 = SMB_BMC_MM7_R_SCL
R257  Q_RES  2.2K 5% CHIP  pkg 0402LF  page 27 : 1 = P3V3_AUX ; 2 = SMB_BMC_MM7_R_SDA
R258  Q_RES  2.2K 5% CHIP  pkg 0402LF  page 27 : 1 = P3V3_AUX ; 2 = SMB_BMC_MM8_SCL
R259  Q_RES  2.2K 5% CHIP  pkg 0402LF  page 27 : 1 = P3V3_AUX ; 2 = SMB_BMC_MM8_SDA
R260  Q_RES  10K 1% CHIP  pkg 0402LF  page 27 : 1 = P3V3_AUX ; 2 = SMB_BMC_MM9_SCL
R261  Q_RES  10K 1% CHIP  pkg 0402LF  page 27 : 1 = P3V3_AUX ; 2 = SMB_BMC_MM9_SDA
R262  Q_RES  10K 1% CHIP  pkg 0402LF  page 27 : 1 = P3V3_AUX ; 2 = SMB_BMC_MM10_SCL
R263  Q_RES  33.2 1% CHIP  pkg 0402LF  page 35 : 1 = RST_MB_STBY_N ; 2 = RST_MB_STBY_R_N
R264  Q_RES  2.2K 5% CHIP  pkg 0402LF  page 27 : 1 = P3V3_AUX ; 2 = SMB_BMC_MM16_SCL
R265  Q_RES  2.2K 5% CHIP  pkg 0402LF  page 27 : 1 = P3V3_AUX ; 2 = SMB_BMC_MM16_SDA
R266  Q_RES  4.7K 1% EMPTY  pkg 0402LF  page 27 : 1 = P3V3_AUX ; 2 = FM_ME_BT_DONE
R267  Q_RES  4.7K 1% EMPTY  pkg 0402LF  page 27 : 1 = P3V3_AUX ; 2 = VOL_SEN_ALERT_R
R268  Q_RES  4.7K 1% CHIP  pkg 0402LF  page 27 : 1 = P3V3_AUX ; 2 = SMB_BMC_ALERT3_N
R269  Q_RES  4.7K 1% CHIP  pkg 0402LF  page 27 : 1 = P3V3_AUX ; 2 = SMB_BMC_ALERT4_N
R270  Q_RES  33.2 1% CHIP  pkg 0402LF  page 34 : 1 = FM_CPU_MSMI_CATERR_LVT3_PLD_N ; 2 = FM_CPU_MSMI_CATERR_LVT3_N
R271  Q_RES  0 5% CHIP  pkg 0402LF  page 35 : 1 = RST_BMC_SELF_HW ; 2 = RST_BMC_SELF_HW_R2
R272  Q_RES  0 5% CHIP  pkg 0402LF  page 34 : 1 = SMB_BMC_MM16_R3_SCL ; 2 = SMB_BMC_MM16_R5_SCL
R273  Q_RES  100K 1% CHIP  pkg 0402LF  page 13 : 1 = PD_CLK_125M_PHY_BMC_RGMII ; 2 = GND
R274  Q_RES  100K 1% EMPTY  pkg 0402LF  page 29 : 1 = P3V3_AUX ; 2 = DEBUG_PORT_UART_RX
R275  Q_RES  0 5% CHIP  pkg 0402LF  page 54 : 1 = PWRGD_P1V8_AUX ; 2 = PWRGD_P1V8_AUX_R
R276  Q_RES  0 5% CHIP  pkg 0402LF  page 55 : 1 = PWRGD_P1V2_AUX_R ; 2 = PWRGD_P1V2_AUX
R277  Q_RES  0 5% CHIP  pkg 0402LF  page 56 : 1 = PWRGD_P1V0_AUX_R ; 2 = PWRGD_P1V0_AUX
R278  Q_RES  0 5% EMPTY  pkg 0402LF  page 17 : 1 = P1V2_AUX ; 2 = P1V2_P1V0_I3C_VDDL1
R279  Q_RES  0 5% CHIP  pkg 0402LF  page 17 : 1 = P1V0_AUX ; 2 = P1V2_P1V0_I3C_VDDL1
R280  Q_RES  0 5% EMPTY  pkg 0402LF  page 17 : 1 = P1V2_AUX ; 2 = P1V2_P1V0_I3C_VDDL2
R281  Q_RES  0 5% CHIP  pkg 0402LF  page 17 : 1 = P1V0_AUX ; 2 = P1V2_P1V0_I3C_VDDL2
R282  Q_RES  0 5% CHIP  pkg 0402LF  page 22 : 1 = RST_BMC_HW_R1 ; 2 = RST_BMC_HW
R283  Q_RES  75 1% CHIP  pkg 0402LF  page 49 : 1 = FM_UARTSW_LSB_N ; 2 = FM_UARTSW_LSB_R1_N
R284  Q_RES  75 1% CHIP  pkg 0402LF  page 49 : 1 = FM_UARTSW_MSB_N ; 2 = FM_UARTSW_MSB_R1_N
R285  Q_RES  4.7K 1% CHIP  pkg 0402LF  page 32 : 1 = JTAG_SCM_PLD_TCK ; 2 = GND
R286  Q_RES  316 1% CHIP  pkg 0402LF  page 50 : 1 = LED_D21_R2 ; 2 = LED_D21_R1
R287  Q_RES  499 1% CHIP  pkg 0402LF  page 22 : 1 = P3V3_RGM ; 2 = RST_BMC_EXTRST_R2_N
R288  Q_RES  10K 1% CHIP  pkg 0402LF  page 36 : 1 = VCCIO2 ; 2 = PU_PB25A
R289  Q_RES  10K 1% CHIP  pkg 0402LF  page 22 : 1 = P3V3_RGM ; 2 = BJT_Q3_C
R290  Q_RES  47K 1% CHIP  pkg 0402LF  page 22 : 1 = BJT_Q3_B ; 2 = RST_BMC_EXTRST_R1_N
R291  Q_RES  4.7K 1% CHIP  pkg 0402LF  page 22 : 1 = P3V3_RGM ; 2 = RST_BMC_EXTRST_R1_N
R292  Q_RES  0 5% CHIP  pkg 0402LF  page 51 : 1 = PWRGD_P5V_AUX_R ; 2 = PWRGD_P5V_AUX
R293  Q_RES  0 5% CHIP  pkg 0402LF  page 52 : 1 = PWRGD_P3V3_AUX_R ; 2 = PWRGD_P3V3_AUX
R294  Q_RES  0 5% CHIP  pkg 0402LF  page 28 : 1 = SMB_BMC_MM15_SDA ; 2 = SMB_BMC_MM15_R1_SDA
R295  Q_RES  10K 1% CHIP  pkg 0402LF  page 28 : 1 = P3V3_AUX ; 2 = DEBUG_PORT_PRSNT_BUF_R_EN
R296  Q_RES  100K 1% EMPTY  pkg 0402LF  page 28 : 1 = DEBUG_PORT_PRSNT_BUF_R_EN ; 2 = GND
R297  Q_RES  10K 1% CHIP  pkg 0402LF  page 34 : 1 = PU_PT20D ; 2 = VCCIO2
R298  Q_RES  4.7K 1% CHIP  pkg 0402LF  page 28 : 1 = P3V3_AUX ; 2 = SMB_DEBUG_AUX_LVC3_USB_R1_SCL
R299  Q_RES  4.7K 1% CHIP  pkg 0402LF  page 28 : 1 = P3V3_AUX ; 2 = SMB_DEBUG_AUX_LVC3_USB_R1_SDA
R300  Q_RES  33.2 1% CHIP  pkg 0402LF  page 28 : 1 = SMB_DEBUG_AUX_LVC3_USB_R1_SCL ; 2 = SMB_DEBUG_AUX_LVC3_USB_SCL
R301  Q_RES  0 5% CHIP  pkg 0402LF  page 41 : 1 = P3V3_AUX ; 2 = VCCIO5
R302  Q_RES  33.2 1% CHIP  pkg 0402LF  page 28 : 1 = SMB_DEBUG_AUX_LVC3_USB_R1_SDA ; 2 = SMB_DEBUG_AUX_LVC3_USB_SDA
R303  Q_RES  0 5% CHIP  pkg 0402LF  page 34 : 1 = SMB_BMC_MM16_R3_SDA ; 2 = SMB_BMC_MM16_R5_SDA
R304  Q_RES  0 5% CHIP  pkg 0402LF  page 41 : 1 = P3V3_AUX ; 2 = VCCIO2
R305  Q_RES  0 5% CHIP  pkg 0402LF  page 41 : 1 = P3V3_AUX ; 2 = VCCIO0
R306  Q_RES  10K 1% CHIP  pkg 0402LF  page 49 : 1 = BEEP_LED ; 2 = GND
R307  Q_RES  0 5% CHIP  pkg 0402LF  page 41 : 1 = P3V3_AUX ; 2 = VCCIO4
R308  Q_RES  0 5% CHIP  pkg 0402LF  page 41 : 1 = P3V3_AUX ; 2 = VCCIO3
R309  Q_RES  33.2 1% CHIP  pkg 0402LF  page 13 : 1 = SPI_BMC_TPM_MOSI_R1 ; 2 = SPI_BMC_TPM_MOSI
R310  Q_RES  33.2 1% CHIP  pkg 0402LF  page 12 : 1 = ESPI_HOST_LPC_BMC_CLK ; 2 = ESPI_HOST_LPC_BMC_CLK_R
R311  Q_RES  33.2 1% CHIP  pkg 0402LF  page 12 : 1 = ESPI_HOST_LPC_BMC_LFRAME_N ; 2 = ESPI_HOST_LPC_BMC_LFRAME_N_R
R312  Q_RES  47K 1% CHIP  pkg 0402LF  page 12 : 1 = RST_BMC_LPC_ESPI_N ; 2 = GND
R313  Q_RES  470K 1% CHIP  pkg 0402LF  page 22 : 1 = RST_BMC_SELF_HW_D ; 2 = GND
R314  Q_RES  100K 1% CHIP  pkg 0402LF  page 22 : 1 = RST_BMC_SELF_HW_D_C ; 2 = GND
R315  Q_RES  0 5% EMPTY  pkg 0402LF  page 22 : 1 = RST_BMC_SRST_BUF_R_N ; 2 = RST_BMC_SRST_BUF_R1_N
R316  Q_RES  0 5% CHIP  pkg 0402LF  page 15 : 1 = BMC_PWR_LED ; 2 = PWR_LED
R317  Q_RES  0 5% CHIP  pkg 0402LF  page 35 : 1 = PWR_LED_CPLD ; 2 = PWR_LED
R318  Q_RES  0 5% CHIP  pkg 0402LF  page 35 : 1 = PWRGD_P3V3_AUX_R1 ; 2 = PWRGD_P3V3_AUX
R319  Q_RES  4.7K 1% CHIP  pkg 0402LF  page 42 : 1 = P3V3_AUX ; 2 = BMC_ID_BEEP_SEL
R320  Q_RES  0 5% CHIP  pkg 0402LF  page 35 : 1 = PWRGD_P2V5_AUX_R1 ; 2 = PWRGD_P2V5_AUX
R321  Q_RES  0 5% CHIP  pkg 0402LF  page 36 : 1 = PWRGD_P1V8_AUX_R1 ; 2 = PWRGD_P1V8_AUX
R322  Q_RES  0 5% CHIP  pkg 0402LF  page 36 : 1 = PWRGD_P3V3_RGM_R1 ; 2 = PWRGD_P3V3_RGM
R323  Q_RES  0 5% CHIP  pkg 0402LF  page 36 : 1 = PWRGD_P1V2_AUX_R1 ; 2 = PWRGD_P1V2_AUX
R324  Q_RES  1K 1% CHIP  pkg 0402LF  page 20 : 1 = P1V2_AUX ; 2 = P0V6_DDR_VREF_AUX
R325  Q_RES  1K 1% CHIP  pkg 0402LF  page 20 : 1 = P0V6_DDR_VREF_AUX ; 2 = GND
R326  Q_RES  120 1% CHIP  pkg 0402LF  page 20 : 1 = GND ; 2 = M_BMC_DDR4_MA<0>
R327  Q_RES  120 1% CHIP  pkg 0402LF  page 20 : 1 = GND ; 2 = M_BMC_DDR4_MA<1>
R328  Q_RES  120 1% CHIP  pkg 0402LF  page 20 : 1 = GND ; 2 = M_BMC_DDR4_MA<2>
R329  Q_RES  120 1% CHIP  pkg 0402LF  page 20 : 1 = GND ; 2 = M_BMC_DDR4_MA<3>
R330  Q_RES  120 1% CHIP  pkg 0402LF  page 20 : 1 = GND ; 2 = M_BMC_DDR4_MA<4>
R331  Q_RES  120 1% CHIP  pkg 0402LF  page 20 : 1 = GND ; 2 = M_BMC_DDR4_MA<5>
R332  Q_RES  120 1% CHIP  pkg 0402LF  page 20 : 1 = GND ; 2 = M_BMC_DDR4_MA<6>
R333  Q_RES  120 1% CHIP  pkg 0402LF  page 20 : 1 = GND ; 2 = M_BMC_DDR4_MA<7>
R334  Q_RES  120 1% CHIP  pkg 0402LF  page 20 : 1 = GND ; 2 = M_BMC_DDR4_MA<8>
R335  Q_RES  120 1% CHIP  pkg 0402LF  page 20 : 1 = GND ; 2 = M_BMC_DDR4_MA<9>
R336  Q_RES  120 1% CHIP  pkg 0402LF  page 20 : 1 = GND ; 2 = M_BMC_DDR4_MA<10>
